Altium Designer Pick and Place Locations
C:\Users\<user>\Desktop\WorkNotes\Projects\PTP\Time-Appliance-Project-master\Time-Card\OSC\OCXO Daughtercard\ECAD\Project Outputs for OCXO_DaughterCard\Pick Place for OCXO_DaughterCard.txt

========================================================================================================================
File Design Information:

Date:       01/07/23
Time:       10:03
Revision:   Not in VersionControl
Variant:    No variations
Units used: mil

Designator Comment                                      Layer       Footprint                                Center-X(mil) Center-Y(mil) Rotation Description                                                                                        
R36        4.7K_1%_0402                                 TopLayer    RESC1005X40X25LL05T05                    1231.299      1926.181      0        "Chip Resistor, 4.7 KOhm, +/- 1%, 0.1 W, -55 to 155 degC, 0402 (1005 Metric), RoHS, Tape and Reel" 
R35        4.7K_1%_0402                                 TopLayer    RESC1005X40X25LL05T05                    1335.630      1924.213      180      "Chip Resistor, 4.7 KOhm, +/- 1%, 0.1 W, -55 to 155 degC, 0402 (1005 Metric), RoHS, Tape and Reel" 
R33        Yageo_RC0201JR-070RL                         TopLayer    RESC0603X026N                            1851.373      1715.458      180      "RES, 0.0 OHM, 0.5A, 1/20W, 0201"                                                                  
C23        "Samsung Electro-Mechanics_CL05B104JO5NNNC"  TopLayer    CAPC1005X055N                            1123.031      1809.646      270      "CAP, CER, X7R, 0.1UF, 5%, 16V, 0402, 0.55MM T"                                                    
C22        Murata_GRM188R61A106ME69D                    TopLayer    CAPC1608X090N                            1067.913      1796.457      270      "CAP, CER, X5R, 10UF, 20%, 10V, 0603, 0.80MM T"                                                    
R34        Yageo_RC0201FR-0710KL                        TopLayer    RESC0603X026N                            948.001       1813.386      270      "RES, 10K OHM, 1%, 1/20W, 200PPM/C, 0201"                                                          
Y5         SiTime_SiT5501AC-WU-33E0-10T                 TopLayer    SITIME_SPL-086-CQFN-010-C07050_REV_DRAFT 1299.213      1776.772      90       "OSC, MEMS, STRATUM 3E, 10.000MHZ, 10PPB STAB, LVCMOS, 3.3V, O/P EN, 7.0X5.0X2.2MM, CQFN-10"       
P14        4871                                         BottomLayer Keystone_4871                            374.015       279.528       180      "Round Standoff Threaded #2-56 Steel 0.063" (1.60mm) 1/16""                                        
P13        4871                                         BottomLayer Keystone_4871                            374.015       1720.472      180      "Round Standoff Threaded #2-56 Steel 0.063" (1.60mm) 1/16""                                        
P16        4871                                         BottomLayer Keystone_4871                            1625.984      1779.528      180      "Round Standoff Threaded #2-56 Steel 0.063" (1.60mm) 1/16""                                        
P15        4871                                         BottomLayer Keystone_4871                            1598.425      161.417       180      "Round Standoff Threaded #2-56 Steel 0.063" (1.60mm) 1/16""                                        
P12        Mill-Max_8600-0-05-80-00-00-03-0             BottomLayer TH001V_109DIA_000mt_8600-0               755.905       1905.512      180      "CONN, PC PIN, PRESS-FIT, 10.16MM LENGTH, TIN, TH"                                                 
P11        Mill-Max_8600-0-05-80-00-00-03-0             BottomLayer TH001V_109DIA_000mt_8600-0               637.795       1905.512      180      "CONN, PC PIN, PRESS-FIT, 10.16MM LENGTH, TIN, TH"                                                 
R32        0_1%_0402                                    BottomLayer RESC1005X40X25NL05T10                    1640.748      762.181       180      ""                                                                                                 
R31        DNI_0_1%_0402                                BottomLayer RESC1005X40X25NL05T10                    1586.614      778.913       270      ""                                                                                                 
R30        0_1%_0402                                    BottomLayer RESC1005X40X25NL05T10                    1554.134      1134.842      90       ""                                                                                                 
R29        DNI_0_1%_0402                                BottomLayer RESC1005X40X25NL05T10                    1537.402      1080.435      180      ""                                                                                                 
R26        0_1%_0402                                    BottomLayer RESC1005X40X25NL05T10                    1289.370      1491.142      90       ""                                                                                                 
R25        0_1%_0402                                    BottomLayer RESC1005X40X25NL05T10                    1300.197      1432.087      0        ""                                                                                                 
R24        0_1%_0402                                    BottomLayer RESC1005X40X25NL05T10                    1301.181      1315.945      0        ""                                                                                                 
R22        DNI_0_1%_0402                                BottomLayer RESC1005X40X25NL05T10                    1332.677      1490.158      270      ""                                                                                                 
R21        DNI_0_1%_0402                                BottomLayer RESC1005X40X25NL05T10                    1301.181      1394.629      180      ""                                                                                                 
R20        DNI_0_1%_0402                                BottomLayer RESC1005X40X25NL05T10                    1301.181      1353.347      180      ""                                                                                                 
R19        0_1%_0402                                    BottomLayer RESC1005X40X25NL05T10                    124.016       1526.417      180      ""                                                                                                 
R18        0_1%_0402                                    BottomLayer RESC1005X40X25NL05T10                    124.016       1487.047      180      ""                                                                                                 
R17        0_1%_0402                                    BottomLayer RESC1005X40X25NL05T10                    124.016       1367.953      180      ""                                                                                                 
R15        DNI_0_1%_0402                                BottomLayer RESC1005X40X25NL05T10                    124.155       1566.772      0        ""                                                                                                 
R28        4.7K_1%_0402                                 TopLayer    RESC1005X40X25LL05T05                    426.181       1824.835      180      "Chip Resistor, 4.7 KOhm, +/- 1%, 0.1 W, -55 to 155 degC, 0402 (1005 Metric), RoHS, Tape and Reel" 
R27        4.7K_1%_0402                                 TopLayer    RESC1005X40X25LL05T05                    502.953       1824.835      0        "Chip Resistor, 4.7 KOhm, +/- 1%, 0.1 W, -55 to 155 degC, 0402 (1005 Metric), RoHS, Tape and Reel" 
R23        0_5%_0603                                    BottomLayer RESC1608X55X25ML10T15                    1070.866      1336.614      180      "Chip Resistor, 0 Ohm, +/- 5%, 0.1 W, -55 to 155 degC, 0603 (1608 Metric), RoHS, Tape and Reel"    
R16        0_5%_0603                                    BottomLayer RESC1608X55X25ML10T15                    452.756       1353.189      180      "Chip Resistor, 0 Ohm, +/- 5%, 0.1 W, -55 to 155 degC, 0603 (1608 Metric), RoHS, Tape and Reel"    
U5         NXP_PCT2075TP,147                            BottomLayer SON50P300X200X80-HS-9N_EP160x160_IPC     1147.299      1449.903      0        "SENSOR DIGITAL -55C-125C 8HWSON"                                                                  
R14        DNI_0_1%_0402                                BottomLayer RESC1005X40X25NL05T10                    124.016       1447.677      0        ""                                                                                                 
R13        DNI_0_1%_0402                                BottomLayer RESC1005X40X25NL05T10                    124.016       1407.323      0        ""                                                                                                 
R12        0_1%_0402                                    BottomLayer RESC1005X40X25NL05T10                    1018.722      766.501       90       ""                                                                                                 
R11        0_1%_0402                                    BottomLayer RESC1005X40X25NL05T10                    959.667       767.564       90       ""                                                                                                 
R10        DNI_0_1%_0402                                BottomLayer RESC1005X40X25NL05T10                    899.130       784.218       0        ""                                                                                                 
R9         DNI_0_1%_0402                                BottomLayer RESC1005X40X25NL05T10                    1081.714      783.234       180      ""                                                                                                 
C21        "Samsung Electro-Mechanics_CL05B104JO5NNNC"  BottomLayer CAPC1005X055N                            1187.008      1376.968      180      "CAP, CER, X7R, 0.1UF, 5%, 16V, 0402, 0.55MM T"                                                    
R7         "Stackpole Electronics, Inc._HCJ0402ZT0R00"  TopLayer    RESC1005X045N                            1799.213      1641.246      90       "RES, 0.0 OHM, 1/8W, 6.5A, 0402"                                                                   
R6         "Stackpole Electronics, Inc._HCJ0402ZT0R00"  TopLayer    RESC1005X045N                            1168.724      1187.425      45       "RES, 0.0 OHM, 1/8W, 6.5A, 0402"                                                                   
Y4         "Rakon_RFPO45 US 10 LF"                      TopLayer    OSC004_600_970x750x430_RFP045            1319.882      1138.780      90       "OSC, OCXO, RFPO45, 10 - 26MHZ, 10PPB STAB, HCMOS, 3.3V, 9.7X7.5X4.3MM, SMT"                       
C20        Murata_GRM188D71A106MA73D                    TopLayer    CAPC1608X100N                            1271.654      861.461       0        "CAP, CER, X7T, 10UF, 20%, 10V, 0603, 1.00MM T"                                                    
C19        "Samsung Electro-Mechanics_CL05B104JO5NNNC"  TopLayer    CAPC1005X055N                            1259.156      913.633       0        "CAP, CER, X7R, 0.1UF, 5%, 16V, 0402, 0.55MM T"                                                    
R8         "Stackpole Electronics, Inc._HCJ0402ZT0R00"  TopLayer    RESC1005X045N                            1780.315      1715.458      0        "RES, 0.0 OHM, 1/8W, 6.5A, 0402"                                                                   
Y3         Abracon_AOCJYR-10.000MHZ-M5625LF             TopLayer    OSC004_600_970x750x410_AOCJYR            1177.166      1374.998      270      "OSC, OCXO, 10.000MHZ, 25PPB STAB, LVCMOS, 3.3V, 9.7X7.5X4.3MM, SMT"                               
C18        Murata_GRM188D71A106MA73D                    BottomLayer CAPC1608X100N                            1273.622      1624.016      0        "CAP, CER, X7T, 10UF, 20%, 10V, 0603, 1.00MM T"                                                    
C17        "Samsung Electro-Mechanics_CL05B104JO5NNNC"  TopLayer    CAPC1005X055N                            1365.158      1474.409      270      "CAP, CER, X7R, 0.1UF, 5%, 16V, 0402, 0.55MM T"                                                    
U1         LMS1587IS-3.3/NOPB                           TopLayer    KTT0003B_L                               1107.061      331.059       0        "3A Low Dropout Fast Response Regulators, 3-pin TO-263, Pb-Free"                                   
R2         DNI_0_1206                                   TopLayer    FP-RC1206-MFG                            572.835       286.417       90       "RES SMD 0 OHM JUMPER 1/4W 1206"                                                                   
C16        Kemet_T491B476K010AT                         TopLayer    CAPMP3528X210N_T520                      283.464       523.032       90       "CAP TANT 47UF 10% 10V 1411"                                                                       
C5         Kemet_T491B476K010AT                         TopLayer    CAPMP3528X210N_T520                      569.882       528.543       90       "CAP TANT 47UF 10% 10V 1411"                                                                       
C15        Kemet_T491B476K010AT                         TopLayer    CAPMP3528X210N_T520                      431.102       523.032       90       "CAP TANT 47UF 10% 10V 1411"                                                                       
FL2        TDK_MPZ1608S601ATA00                         BottomLayer INDC1608X095N                            789.961       720.296       90       "FERRITE BEAD, 600 OHM @100MHZ, 25%, 1A, 0.150 OHM DCR, 0603, 0.95MM T"                            
FL1        TDK_MPZ1608S601ATA00                         BottomLayer INDC1608X095N                            868.597       1262.008      270      "FERRITE BEAD, 600 OHM @100MHZ, 25%, 1A, 0.150 OHM DCR, 0603, 0.95MM T"                            
U4         TI_DS90LV028AQMA/NOPB                        BottomLayer SOP127P600X175_8N                        568.898       922.441       0        "IC, RVCR, DS90LV028AQ-Q1, DUAL, DIFF, LVDS, 400MBPS, SOIC-8"                                      
U3         TI_DS90LV027AQMA/NOPB                        BottomLayer SOP127P600X175_8N                        567.913       1155.512      180      "IC, DRIVER, DS90LV027AQ, DUAL, DIFF, LVDS, 600MBPS, SOIC-8"                                       
R5         Yageo_RC0402FR-07100RL                       BottomLayer RESC1005X040N                            389.764       871.850       90       "RES SMD 100 OHM 1% 1/16W 0402"                                                                    
C14        Yageo_CC0402KRX7R7BB103                      BottomLayer CAPC1005X055N                            675.266       736.614       270      "CAP, CER, X7R, 0.01UF, 10%, 16V, 0402, 0.55MM T"                                                  
C13        "Samsung Electro-Mechanics_CL05B104JO5NNNC"  BottomLayer CAPC1005X055N                            726.012       735.236       270      "CAP, CER, X7R, 0.1UF, 5%, 16V, 0402, 0.55MM T"                                                    
C12        Yageo_CC0402KRX7R7BB103                      BottomLayer CAPC1005X055N                            814.088       1248.622      90       "CAP, CER, X7R, 0.01UF, 10%, 16V, 0402, 0.55MM T"                                                  
C11        "Samsung Electro-Mechanics_CL05B104JO5NNNC"  BottomLayer CAPC1005X055N                            760.500       1248.622      90       "CAP, CER, X7R, 0.1UF, 5%, 16V, 0402, 0.55MM T"                                                    
Y2         SiTime_SiT5711AC-KW-33E-10                   TopLayer    SON150P700X619-10N_SiT5711               958.662       987.445       90       "OSC, OCXO, 10.000MHZ, 5PPM STAB, LVCMOS/CLIPPED SINE, 3.3V, DFN-10"                               
R4         Panasonic_ERJ-2RKF1003X                      TopLayer    RESC1005X040N                            859.449       774.694       180      "RES, 100K OHM, 1%, 1/10W, 100PPM/C, 0402"                                                         
C10        Murata_GRM188D71A106MA73D                    TopLayer    CAPC1608X100N                            872.047       1216.776      0        "CAP, CER, X7T, 10UF, 20%, 10V, 0603, 1.00MM T"                                                    
C9         "Samsung Electro-Mechanics_CL05B104JO5NNNC"  TopLayer    CAPC1005X055N                            858.661       1163.626      0        "CAP, CER, X7R, 0.1UF, 5%, 16V, 0402, 0.55MM T"                                                    
C8         Murata_GRM188D71A106MA73D                    BottomLayer CAPC1608X100N                            1505.906      1531.842      180      "CAP, CER, X7T, 10UF, 20%, 10V, 0603, 1.00MM T"                                                    
C7         "Samsung Electro-Mechanics_CL05B104JO5NNNC"  TopLayer    CAPC1005X055N                            1697.507      1494.289      270      "CAP, CER, X7R, 0.1UF, 5%, 16V, 0402, 0.55MM T"                                                    
Y1         Rakon_ROD2522S2                              TopLayer    OSC007_762_2540x2200x1230                1121.838      1163.271      180      "OSC, OCXO, 10MHZ - 20MHZ, 0.5PPB STAB, 3.3V, 22.0X25.4X12.3MM, SMT"                               
U2         Microchip_AT24MAC602-XHM-B                   BottomLayer TSSOP65P640X120-8N                       368.576       1499.761      0        "IC, EEPROM, AT24MAC602, 2K-BIT (256 X 8), 1MHZ, I2C, 1.7V - 5.5V, TSSOP-8"                        
C6         "Samsung Electro-Mechanics_CL05B104JO5NNNC"  BottomLayer CAPC1005X055N                            464.663       1410.936      180      "CAP, CER, X7R, 0.1UF, 5%, 16V, 0402, 0.55MM T"                                                    
P10        Molex_539160208                              BottomLayer SM020V_50_730x310x337_000mt_53916        212.599       1000.000      90       "CONN, B2B/FPC, HEADER, 20-POS, 0.5MM PITCH, 4.0MM H, VERT, GOLD, SMT"                             
J2         Wurth_9774040243R                            BottomLayer TH000V_300DIAx400_001mt_9774040243R      1830.709      543.307       180      "STANDOFF, ROUND, M2X0.4 STEEL 4MM, 9774040243R"                                                   
J1         Wurth_9774040243R                            BottomLayer TH000V_300DIAx400_001mt_9774040243R      1830.709      1374.016      180      "STANDOFF, ROUND, M2X0.4 STEEL 4MM, 9774040243R"                                                   
R1         "Stackpole Electronics, Inc._RMCF1210ZT0R00" TopLayer    RESC3225X070N                            134.842       469.488       90       "RES, 0.0 OHM, 3A, 1/2W, 1210"                                                                     
P9         Samtec_HTSW-102-07-T-S                       TopLayer    TH002_254_508x254x838_000mt_HTSW         184.842       704.724       0        "CONN, PIN, HEADER, 2POS, 2.54MM PITCH, 8.38MM H, VERT, TIN, TH"                                   
C4         Murata_GRM21BR61A226ME51L                    TopLayer    CAPC2013X140N                            756.890       186.024       270      "CAP, CER, X5R, 22UF, 20%, 10V, 0805, 1.40MM T"                                                    
C3         Murata_GRM21BR61A226ME51L                    TopLayer    CAPC2013X140N                            170.276       833.661       0        "CAP, CER, X5R, 22UF, 20%, 10V, 0805, 1.40MM T"                                                    
C2         Murata_GRM21BR61A226ME51L                    TopLayer    CAPC2013X140N                            170.276       933.071       0        "CAP, CER, X5R, 22UF, 20%, 10V, 0805, 1.40MM T"                                                    
C1         "Samsung Electro-Mechanics_CL05B104JO5NNNC"  TopLayer    CAPC1005X055N                            664.370       186.181       270      "CAP, CER, X7R, 0.1UF, 5%, 16V, 0402, 0.55MM T"                                                    
P5         Mill-Max_8600-0-05-80-00-00-03-0             BottomLayer TH001V_109DIA_000mt_8600-0               200.787       200.787       180      "CONN, PC PIN, PRESS-FIT, 10.16MM LENGTH, TIN, TH"                                                 
P4         Mill-Max_8600-0-05-80-00-00-03-0             BottomLayer TH001V_109DIA_000mt_8600-0               1799.213      1000.000      180      "CONN, PC PIN, PRESS-FIT, 10.16MM LENGTH, TIN, TH"                                                 
P6         Mill-Max_8600-0-05-80-00-00-03-0             BottomLayer TH001V_109DIA_000mt_8600-0               283.465       1905.512      180      "CONN, PC PIN, PRESS-FIT, 10.16MM LENGTH, TIN, TH"                                                 
P8         Mill-Max_8600-0-05-80-00-00-03-0             BottomLayer TH001V_109DIA_000mt_8600-0               401.575       1905.512      180      "CONN, PC PIN, PRESS-FIT, 10.16MM LENGTH, TIN, TH"                                                 
P7         Mill-Max_8600-0-05-80-00-00-03-0             BottomLayer TH001V_109DIA_000mt_8600-0               519.685       1905.512      180      "CONN, PC PIN, PRESS-FIT, 10.16MM LENGTH, TIN, TH"                                                 
P3         Mill-Max_8600-0-05-80-00-00-03-0             BottomLayer TH001V_109DIA_000mt_8600-0               1799.213      1799.213      180      "CONN, PC PIN, PRESS-FIT, 10.16MM LENGTH, TIN, TH"                                                 
P1         Mill-Max_8600-0-05-80-00-00-03-0             BottomLayer TH001V_109DIA_000mt_8600-0               1799.213      200.787       180      "CONN, PC PIN, PRESS-FIT, 10.16MM LENGTH, TIN, TH"                                                 
P2         Mill-Max_8600-0-05-80-00-00-03-0             BottomLayer TH001V_109DIA_000mt_8600-0               200.787       1799.213      180      "CONN, PC PIN, PRESS-FIT, 10.16MM LENGTH, TIN, TH"                                                 
